# SCM (Grand Teton) — schematic netlist excerpt (pin names and nets, part order shuffled) for the footprints in the layout excerpt that follows; sources: Cadence DE-HDL packaged netlist, KiCad conversion of 12092022_DA0F0TMDCD0_F0T_Management_Board_D_brd_V3_OCP.brd

R857  Q_RES  1K 1% EMPTY  pkg 0402LF  page 14 : A = FM_BOARD_BMC_REV_ID1 ; B = GND
R646  Q_RES  0 5% EMPTY  pkg 0603LF  page 17 : A = PGPPA_BMC_AUX_L ; B = P3V3_AUX

(kicad_pcb
	(version 20260206)
	(generator "pcbnew")
	(generator_version "10.0")
	(general
		(thickness 1.6)
		(legacy_teardrops no)
	)
	(paper "A4")
	(title_block
		(title "12092022_DA0F0TMDCD0_F0T_Management_Board_D_brd_V3_OCP.brd")
		(comment 1 "Grand Teton / footprints 1012-1013 of 1440")
	)
	(layers
		(0 "F.Cu" signal "TOP")
		(4 "In1.Cu" signal "GND")
		(6 "In2.Cu" signal "IN1")
		(8 "In3.Cu" signal "GND1")
		(10 "In4.Cu" signal "IN2")
		(12 "In5.Cu" signal "VCC")
		(14 "In6.Cu" signal "VCC1")
		(16 "In7.Cu" signal "IN3")
		(18 "In8.Cu" signal "GND2")
		(20 "In9.Cu" signal "IN4")
		(22 "In10.Cu" signal "GND3")
		(2 "B.Cu" signal "BOTTOM")
		(9 "F.Adhes" user "F.Adhesive")
		(11 "B.Adhes" user "B.Adhesive")
		(13 "F.Paste" user "Package Geometry/Pastemask Top")
		(15 "B.Paste" user "Package Geometry/Pastemask Bottom")
		(5 "F.SilkS" user "Ref Des/Silkscreen Top")
		(7 "B.SilkS" user "Ref Des/Silkscreen Bottom")
		(1 "F.Mask" user "Board Geometry/Soldermask Top")
		(3 "B.Mask" user "Board Geometry/Soldermask Bottom")
		(17 "Dwgs.User" user "User.Drawings")
		(19 "Cmts.User" user "User.Comments")
		(21 "Eco1.User" user "User.Eco1")
		(23 "Eco2.User" user "User.Eco2")
		(25 "Edge.Cuts" user "Board Geometry/Outline")
		(27 "Margin" user)
		(31 "F.CrtYd" user "Package Geometry/Place Bound Top")
		(29 "B.CrtYd" user "Package Geometry/Place Bound Bottom")
		(35 "F.Fab" user "Ref Des/Assembly Top")
		(33 "B.Fab" user "Ref Des/Assembly Bottom")
	)
	(footprint ""
		(layer "B.Cu")
		(at 71.374 -19.685 90)
		(property "Reference" "R857"
			(at 0 0 90)
			(layer "B.SilkS")
			(hide yes)
			(effects
				(font
					(size 1.27 1.27)
				)
				(justify mirror)
			)
		)
		(property "Value" ""
			(at 0 0 90)
			(layer "B.Fab")
			(effects
				(font
					(size 1.27 1.27)
				)
				(justify mirror)
			)
		)
		(duplicate_pad_numbers_are_jumpers no)
		(fp_line
			(start 0.7874 -0.4064)
			(end -0.7874 -0.4064)
			(stroke
				(width 0.1524)
				(type default)
			)
			(layer "B.SilkS")
		)
		(fp_line
			(start -0.7874 -0.4064)
			(end -0.7874 0.4064)
			(stroke
				(width 0.1524)
				(type default)
			)
			(layer "B.SilkS")
		)
		(fp_line
			(start 0.7874 0.4064)
			(end 0.7874 -0.4064)
			(stroke
				(width 0.1524)
				(type default)
			)
			(layer "B.SilkS")
		)
		(fp_line
			(start -0.7874 0.4064)
			(end 0.7874 0.4064)
			(stroke
				(width 0.1524)
				(type default)
			)
			(layer "B.SilkS")
		)
		(fp_line
			(start 0.67945 -0.305054)
			(end 0.12065 -0.305054)
			(stroke
				(width 0.1)
				(type default)
			)
			(layer "B.Fab")
		)
		(fp_line
			(start 0.12065 -0.305054)
			(end 0.12065 -0.2794)
			(stroke
				(width 0.1)
				(type default)
			)
			(layer "B.Fab")
		)
		(fp_line
			(start -0.12065 -0.3048)
			(end -0.67945 -0.3048)
			(stroke
				(width 0.1)
				(type default)
			)
			(layer "B.Fab")
		)
		(fp_line
			(start -0.67945 -0.3048)
			(end -0.67945 0.3048)
			(stroke
				(width 0.1)
				(type default)
			)
			(layer "B.Fab")
		)
		(fp_line
			(start 0.12065 -0.2794)
			(end -0.12065 -0.2794)
			(stroke
				(width 0.1)
				(type default)
			)
			(layer "B.Fab")
		)
		(fp_line
			(start -0.12065 -0.2794)
			(end -0.12065 -0.3048)
			(stroke
				(width 0.1)
				(type default)
			)
			(layer "B.Fab")
		)
		(fp_line
			(start 0.12065 0.2794)
			(end 0.12065 0.3048)
			(stroke
				(width 0.1)
				(type default)
			)
			(layer "B.Fab")
		)
		(fp_line
			(start -0.120396 0.2794)
			(end 0.12065 0.2794)
			(stroke
				(width 0.1)
				(type default)
			)
			(layer "B.Fab")
		)
		(fp_line
			(start 0.67945 0.3048)
			(end 0.67945 -0.305054)
			(stroke
				(width 0.1)
				(type default)
			)
			(layer "B.Fab")
		)
		(fp_line
			(start 0.12065 0.3048)
			(end 0.67945 0.3048)
			(stroke
				(width 0.1)
				(type default)
			)
			(layer "B.Fab")
		)
		(fp_line
			(start -0.120396 0.3048)
			(end -0.120396 0.2794)
			(stroke
				(width 0.1)
				(type default)
			)
			(layer "B.Fab")
		)
		(fp_line
			(start -0.67945 0.3048)
			(end -0.120396 0.3048)
			(stroke
				(width 0.1)
				(type default)
			)
			(layer "B.Fab")
		)
		(pad "1" smd circle
			(at 0.40005 0 270)
			(size 0 0)
			(layers "B.Cu" "B.Mask" "B.Paste")
			(net "FM_BOARD_BMC_REV_ID1")
		)
		(pad "2" smd circle
			(at -0.40005 0 270)
			(size 0 0)
			(layers "B.Cu" "B.Mask" "B.Paste")
			(net "GND")
		)
	)
	(footprint ""
		(layer "B.Cu")
		(at 65.89014 -97.6376 180)
		(property "Reference" "R646"
			(at 0 0 0)
			(layer "B.SilkS")
			(hide yes)
			(effects
				(font
					(size 1.27 1.27)
				)
				(justify mirror)
			)
		)
		(property "Value" ""
			(at 0 0 0)
			(layer "B.Fab")
			(effects
				(font
					(size 1.27 1.27)
				)
				(justify mirror)
			)
		)
		(duplicate_pad_numbers_are_jumpers no)
		(fp_line
			(start 1.2954 0.5842)
			(end 1.2954 -0.5842)
			(stroke
				(width 0.1524)
				(type default)
			)
			(layer "B.SilkS")
		)
		(fp_line
			(start 1.2954 -0.5842)
			(end -1.2954 -0.5842)
			(stroke
				(width 0.1524)
				(type default)
			)
			(layer "B.SilkS")
		)
		(fp_line
			(start -1.2954 0.5842)
			(end 1.2954 0.5842)
			(stroke
				(width 0.1524)
				(type default)
			)
			(layer "B.SilkS")
		)
		(fp_line
			(start -1.2954 -0.5842)
			(end -1.2954 0.5842)
			(stroke
				(width 0.1524)
				(type default)
			)
			(layer "B.SilkS")
		)
		(fp_line
			(start 1.1938 0.4064)
			(end 1.1938 -0.406654)
			(stroke
				(width 0.1)
				(type default)
			)
			(layer "B.Fab")
		)
		(fp_line
			(start 1.1938 -0.406654)
			(end 0.8636 -0.406654)
			(stroke
				(width 0.1)
				(type default)
			)
			(layer "B.Fab")
		)
		(fp_line
			(start 0.8636 0.4572)
			(end 0.8636 0.4318)
			(stroke
				(width 0.1)
				(type default)
			)
			(layer "B.Fab")
		)
		(fp_line
			(start 0.8636 0.4318)
			(end 0.8636 0.4064)
			(stroke
				(width 0.1)
				(type default)
			)
			(layer "B.Fab")
		)
		(fp_line
			(start 0.8636 0.4064)
			(end 1.1938 0.4064)
			(stroke
				(width 0.1)
				(type default)
			)
			(layer "B.Fab")
		)
		(fp_line
			(start 0.8636 -0.406654)
			(end 0.8636 -0.4572)
			(stroke
				(width 0.1)
				(type default)
			)
			(layer "B.Fab")
		)
		(fp_line
			(start 0.8636 -0.4572)
			(end -0.8636 -0.4572)
			(stroke
				(width 0.1)
				(type default)
			)
			(layer "B.Fab")
		)
		(fp_line
			(start -0.8636 0.4572)
			(end 0.8636 0.4572)
			(stroke
				(width 0.1)
				(type default)
			)
			(layer "B.Fab")
		)
		(fp_line
			(start -0.8636 0.4064)
			(end -0.8636 0.4572)
			(stroke
				(width 0.1)
				(type default)
			)
			(layer "B.Fab")
		)
		(fp_line
			(start -0.8636 -0.406654)
			(end -1.1938 -0.406654)
			(stroke
				(width 0.1)
				(type default)
			)
			(layer "B.Fab")
		)
		(fp_line
			(start -0.8636 -0.4572)
			(end -0.8636 -0.406654)
			(stroke
				(width 0.1)
				(type default)
			)
			(layer "B.Fab")
		)
		(fp_line
			(start -1.1938 0.4064)
			(end -0.8636 0.4064)
			(stroke
				(width 0.1)
				(type default)
			)
			(layer "B.Fab")
		)
		(fp_line
			(start -1.1938 -0.406654)
			(end -1.1938 0.4064)
			(stroke
				(width 0.1)
				(type default)
			)
			(layer "B.Fab")
		)
		(pad "1" smd rect
			(at 0.7366 0 90)
			(size 0.7112 0.8128)
			(layers "B.Cu" "B.Mask" "B.Paste")
			(net "PGPPA_BMC_AUX_L")
		)
		(pad "2" smd rect
			(at -0.7366 0 90)
			(size 0.7112 0.8128)
			(layers "B.Cu" "B.Mask" "B.Paste")
			(net "P3V3_AUX")
		)
	)
)
